# S9S_MB_2U (Grand Teton) — schematic netlist excerpt (pin names and nets, part order shuffled) for the footprints in the layout excerpt that follows; sources: Cadence DE-HDL packaged netlist, KiCad conversion of 03242023_DA0F0TMBIJ0_F0T_Motherboard_J_brd_V01_OCP.brd

ME13  ME_DUMMY_SYMBOL  PICKUP_SMDC20 EMPTY  pkg PICKUP_SMDC20  page 312
R3526  Q_RES  0 5% CHIP  pkg 0402LF  page 231 : A = SMB_PCIE0_3V3AUX_SCL_R5 ; B = SMB_SENSOR_E1S_3V3AUX_SCL
PR1782  Q_RES  3.3 1% CHIP  pkg 0402LF  page 272 : A = SW_PVCCFA_EHV_FIVRA_CPU0_BOOT3 ; B = SW_PVCCFA_EHV_FIVRA_CPU0_BOOT3_

(kicad_pcb
	(version 20260206)
	(generator "pcbnew")
	(generator_version "10.0")
	(general
		(thickness 1.6)
		(legacy_teardrops no)
	)
	(paper "A4")
	(title_block
		(title "03242023_DA0F0TMBIJ0_F0T_Motherboard_J_brd_V01_OCP.brd")
		(comment 1 "Grand Teton / footprints 268-270 of 6105")
	)
	(layers
		(0 "F.Cu" signal "TOP")
		(4 "In1.Cu" signal "GND")
		(6 "In2.Cu" signal "IN1")
		(8 "In3.Cu" signal "GND1")
		(10 "In4.Cu" signal "IN2")
		(12 "In5.Cu" signal "GND2")
		(14 "In6.Cu" signal "IN3")
		(16 "In7.Cu" signal "GND3")
		(18 "In8.Cu" signal "VCC")
		(20 "In9.Cu" signal "VCC1")
		(22 "In10.Cu" signal "GND4")
		(24 "In11.Cu" signal "IN4")
		(26 "In12.Cu" signal "GND5")
		(28 "In13.Cu" signal "IN5")
		(30 "In14.Cu" signal "GND6")
		(32 "In15.Cu" signal "IN6")
		(34 "In16.Cu" signal "GND7")
		(2 "B.Cu" signal "BOTTOM")
		(9 "F.Adhes" user "F.Adhesive")
		(11 "B.Adhes" user "B.Adhesive")
		(13 "F.Paste" user "Package Geometry/Pastemask Top")
		(15 "B.Paste" user "Package Geometry/Pastemask Bottom")
		(5 "F.SilkS" user "Ref Des/Silkscreen Top")
		(7 "B.SilkS" user "Ref Des/Silkscreen Bottom")
		(1 "F.Mask" user "Board Geometry/Soldermask Top")
		(3 "B.Mask" user "Board Geometry/Soldermask Bottom")
		(17 "Dwgs.User" user "User.Drawings")
		(19 "Cmts.User" user "User.Comments")
		(21 "Eco1.User" user "User.Eco1")
		(23 "Eco2.User" user "User.Eco2")
		(25 "Edge.Cuts" user "Board Geometry/Outline")
		(27 "Margin" user)
		(31 "F.CrtYd" user "Package Geometry/Place Bound Top")
		(29 "B.CrtYd" user "Package Geometry/Place Bound Bottom")
		(35 "F.Fab" user "Ref Des/Assembly Top")
		(33 "B.Fab" user "Ref Des/Assembly Bottom")
	)
	(footprint ""
		(layer "F.Cu")
		(at 113.494312 -128.392682 180)
		(property "Reference" "R3526"
			(at 0 0 180)
			(layer "F.SilkS")
			(hide yes)
			(effects
				(font
					(size 1.27 1.27)
				)
			)
		)
		(property "Value" ""
			(at 0 0 180)
			(layer "F.Fab")
			(effects
				(font
					(size 1.27 1.27)
				)
			)
		)
		(duplicate_pad_numbers_are_jumpers no)
		(fp_line
			(start 0.7874 0.4064)
			(end -0.7874 0.4064)
			(stroke
				(width 0.1524)
				(type default)
			)
			(layer "F.SilkS")
		)
		(fp_line
			(start 0.7874 -0.4064)
			(end 0.7874 0.4064)
			(stroke
				(width 0.1524)
				(type default)
			)
			(layer "F.SilkS")
		)
		(fp_line
			(start -0.7874 0.4064)
			(end -0.7874 -0.4064)
			(stroke
				(width 0.1524)
				(type default)
			)
			(layer "F.SilkS")
		)
		(fp_line
			(start -0.7874 -0.4064)
			(end 0.7874 -0.4064)
			(stroke
				(width 0.1524)
				(type default)
			)
			(layer "F.SilkS")
		)
		(fp_line
			(start 0.67945 0.3048)
			(end 0.120396 0.3048)
			(stroke
				(width 0.1)
				(type default)
			)
			(layer "F.Fab")
		)
		(fp_line
			(start 0.67945 -0.3048)
			(end 0.67945 0.3048)
			(stroke
				(width 0.1)
				(type default)
			)
			(layer "F.Fab")
		)
		(fp_line
			(start 0.12065 -0.2794)
			(end 0.12065 -0.3048)
			(stroke
				(width 0.1)
				(type default)
			)
			(layer "F.Fab")
		)
		(fp_line
			(start 0.12065 -0.3048)
			(end 0.67945 -0.3048)
			(stroke
				(width 0.1)
				(type default)
			)
			(layer "F.Fab")
		)
		(fp_line
			(start 0.120396 0.3048)
			(end 0.120396 0.2794)
			(stroke
				(width 0.1)
				(type default)
			)
			(layer "F.Fab")
		)
		(fp_line
			(start 0.120396 0.2794)
			(end -0.12065 0.2794)
			(stroke
				(width 0.1)
				(type default)
			)
			(layer "F.Fab")
		)
		(fp_line
			(start -0.12065 0.3048)
			(end -0.67945 0.3048)
			(stroke
				(width 0.1)
				(type default)
			)
			(layer "F.Fab")
		)
		(fp_line
			(start -0.12065 0.2794)
			(end -0.12065 0.3048)
			(stroke
				(width 0.1)
				(type default)
			)
			(layer "F.Fab")
		)
		(fp_line
			(start -0.12065 -0.2794)
			(end 0.12065 -0.2794)
			(stroke
				(width 0.1)
				(type default)
			)
			(layer "F.Fab")
		)
		(fp_line
			(start -0.12065 -0.305054)
			(end -0.12065 -0.2794)
			(stroke
				(width 0.1)
				(type default)
			)
			(layer "F.Fab")
		)
		(fp_line
			(start -0.67945 0.3048)
			(end -0.67945 -0.305054)
			(stroke
				(width 0.1)
				(type default)
			)
			(layer "F.Fab")
		)
		(fp_line
			(start -0.67945 -0.305054)
			(end -0.12065 -0.305054)
			(stroke
				(width 0.1)
				(type default)
			)
			(layer "F.Fab")
		)
		(pad "1" smd circle
			(at -0.40005 0 180)
			(size 0 0)
			(layers "F.Cu" "F.Mask" "F.Paste")
			(net "SMB_PCIE0_3V3AUX_SCL_R5")
		)
		(pad "2" smd circle
			(at 0.40005 0 180)
			(size 0 0)
			(layers "F.Cu" "F.Mask" "F.Paste")
			(net "SMB_SENSOR_E1S_3V3AUX_SCL")
		)
	)
	(footprint ""
		(layer "F.Cu")
		(at 426.607986 -366.691164 90)
		(property "Reference" "PR1782"
			(at 0 0 90)
			(layer "F.SilkS")
			(hide yes)
			(effects
				(font
					(size 1.27 1.27)
				)
			)
		)
		(property "Value" ""
			(at 0 0 90)
			(layer "F.Fab")
			(effects
				(font
					(size 1.27 1.27)
				)
			)
		)
		(duplicate_pad_numbers_are_jumpers no)
		(fp_line
			(start 0.7874 -0.4064)
			(end 0.7874 0.4064)
			(stroke
				(width 0.1524)
				(type default)
			)
			(layer "F.SilkS")
		)
		(fp_line
			(start -0.7874 -0.4064)
			(end 0.7874 -0.4064)
			(stroke
				(width 0.1524)
				(type default)
			)
			(layer "F.SilkS")
		)
		(fp_line
			(start 0.7874 0.4064)
			(end -0.7874 0.4064)
			(stroke
				(width 0.1524)
				(type default)
			)
			(layer "F.SilkS")
		)
		(fp_line
			(start -0.7874 0.4064)
			(end -0.7874 -0.4064)
			(stroke
				(width 0.1524)
				(type default)
			)
			(layer "F.SilkS")
		)
		(fp_line
			(start -0.12065 -0.305054)
			(end -0.12065 -0.2794)
			(stroke
				(width 0.1)
				(type default)
			)
			(layer "F.Fab")
		)
		(fp_line
			(start -0.67945 -0.305054)
			(end -0.12065 -0.305054)
			(stroke
				(width 0.1)
				(type default)
			)
			(layer "F.Fab")
		)
		(fp_line
			(start 0.67945 -0.3048)
			(end 0.67945 0.3048)
			(stroke
				(width 0.1)
				(type default)
			)
			(layer "F.Fab")
		)
		(fp_line
			(start 0.12065 -0.3048)
			(end 0.67945 -0.3048)
			(stroke
				(width 0.1)
				(type default)
			)
			(layer "F.Fab")
		)
		(fp_line
			(start 0.12065 -0.2794)
			(end 0.12065 -0.3048)
			(stroke
				(width 0.1)
				(type default)
			)
			(layer "F.Fab")
		)
		(fp_line
			(start -0.12065 -0.2794)
			(end 0.12065 -0.2794)
			(stroke
				(width 0.1)
				(type default)
			)
			(layer "F.Fab")
		)
		(fp_line
			(start 0.120396 0.2794)
			(end -0.12065 0.2794)
			(stroke
				(width 0.1)
				(type default)
			)
			(layer "F.Fab")
		)
		(fp_line
			(start -0.12065 0.2794)
			(end -0.12065 0.3048)
			(stroke
				(width 0.1)
				(type default)
			)
			(layer "F.Fab")
		)
		(fp_line
			(start 0.67945 0.3048)
			(end 0.120396 0.3048)
			(stroke
				(width 0.1)
				(type default)
			)
			(layer "F.Fab")
		)
		(fp_line
			(start 0.120396 0.3048)
			(end 0.120396 0.2794)
			(stroke
				(width 0.1)
				(type default)
			)
			(layer "F.Fab")
		)
		(fp_line
			(start -0.12065 0.3048)
			(end -0.67945 0.3048)
			(stroke
				(width 0.1)
				(type default)
			)
			(layer "F.Fab")
		)
		(fp_line
			(start -0.67945 0.3048)
			(end -0.67945 -0.305054)
			(stroke
				(width 0.1)
				(type default)
			)
			(layer "F.Fab")
		)
		(pad "1" smd circle
			(at -0.40005 0 90)
			(size 0 0)
			(layers "F.Cu" "F.Mask" "F.Paste")
			(net "SW_PVCCFA_EHV_FIVRA_CPU0_BOOT3")
		)
		(pad "2" smd circle
			(at 0.40005 0 90)
			(size 0 0)
			(layers "F.Cu" "F.Mask" "F.Paste")
			(net "SW_PVCCFA_EHV_FIVRA_CPU0_BOOT3_")
		)
	)
	(footprint ""
		(layer "F.Cu")
		(at 391.36828 -121.15546)
		(property "Reference" "ME13"
			(at -9.652 -9.540748 0)
			(unlocked yes)
			(layer "F.SilkS")
			(effects
				(font
					(size 0.7874 0.5842)
					(thickness 0.1524)
				)
				(justify left)
			)
		)
		(property "Value" ""
			(at 0 0 0)
			(layer "F.Fab")
			(effects
				(font
					(size 1.27 1.27)
				)
			)
		)
		(duplicate_pad_numbers_are_jumpers no)
		(zone
			(layer "F.Cu")
			(hatch none 0.5)
			(connect_pads
				(clearance 0)
			)
			(min_thickness 0.25)
			(keepout
				(tracks allowed)
				(vias allowed)
				(pads allowed)
				(copperpour allowed)
				(footprints not_allowed)
			)
			(placement
				(enabled no)
				(sheetname "")
			)
			(fill
				(thermal_gap 0.5)
				(thermal_bridge_width 0.5)
				(island_removal_mode 0)
			)
			(polygon
				(pts
					(arc
						(start 401.36826 -121.15546)
						(mid 381.3683 -121.15546)
						(end 401.36826 -121.15546)
					)
				)
			)
		)
	)
)
